(kicad_pcb
	(version 20260206)
	(generator "pcbnew")
	(generator_version "10.0")
	(general
		(thickness 1.6)
		(legacy_teardrops no)
	)
	(paper "A4")
	(title_block
		(title "03242023_DA0F0TMBIJ0_F0T_Motherboard_J_brd_V01_OCP.brd")
		(comment 1 "Grand Teton / footprints 1250-1251 of 6105")
	)
	(layers
		(0 "F.Cu" signal "TOP")
		(4 "In1.Cu" signal "GND")
		(6 "In2.Cu" signal "IN1")
		(8 "In3.Cu" signal "GND1")
		(10 "In4.Cu" signal "IN2")
		(12 "In5.Cu" signal "GND2")
		(14 "In6.Cu" signal "IN3")
		(16 "In7.Cu" signal "GND3")
		(18 "In8.Cu" signal "VCC")
		(20 "In9.Cu" signal "VCC1")
		(22 "In10.Cu" signal "GND4")
		(24 "In11.Cu" signal "IN4")
		(26 "In12.Cu" signal "GND5")
		(28 "In13.Cu" signal "IN5")
		(30 "In14.Cu" signal "GND6")
		(32 "In15.Cu" signal "IN6")
		(34 "In16.Cu" signal "GND7")
		(2 "B.Cu" signal "BOTTOM")
		(9 "F.Adhes" user "F.Adhesive")
		(11 "B.Adhes" user "B.Adhesive")
		(13 "F.Paste" user "Package Geometry/Pastemask Top")
		(15 "B.Paste" user "Package Geometry/Pastemask Bottom")
		(5 "F.SilkS" user "Ref Des/Silkscreen Top")
		(7 "B.SilkS" user "Ref Des/Silkscreen Bottom")
		(1 "F.Mask" user "Board Geometry/Soldermask Top")
		(3 "B.Mask" user "Board Geometry/Soldermask Bottom")
		(17 "Dwgs.User" user "User.Drawings")
		(19 "Cmts.User" user "User.Comments")
		(21 "Eco1.User" user "User.Eco1")
		(23 "Eco2.User" user "User.Eco2")
		(25 "Edge.Cuts" user "Board Geometry/Outline")
		(27 "Margin" user)
		(31 "F.CrtYd" user "Package Geometry/Place Bound Top")
		(29 "B.CrtYd" user "Package Geometry/Place Bound Bottom")
		(35 "F.Fab" user "Ref Des/Assembly Top")
		(33 "B.Fab" user "Ref Des/Assembly Bottom")
	)
	(footprint ""
		(layer "F.Cu")
		(at 207.43418 -127.996188 90)
		(property "Reference" "R2531"
			(at 0 0 90)
			(layer "F.SilkS")
			(hide yes)
			(effects
				(font
					(size 1.27 1.27)
				)
			)
		)
		(property "Value" ""
			(at 0 0 90)
			(layer "F.Fab")
			(effects
				(font
					(size 1.27 1.27)
				)
			)
		)
		(duplicate_pad_numbers_are_jumpers no)
		(fp_line
			(start 0.7874 -0.4064)
			(end 0.7874 0.4064)
			(stroke
				(width 0.1524)
				(type default)
			)
			(layer "F.SilkS")
		)
		(fp_line
			(start -0.7874 -0.4064)
			(end 0.7874 -0.4064)
			(stroke
				(width 0.1524)
				(type default)
			)
			(layer "F.SilkS")
		)
		(fp_line
			(start 0.7874 0.4064)
			(end -0.7874 0.4064)
			(stroke
				(width 0.1524)
				(type default)
			)
			(layer "F.SilkS")
		)
		(fp_line
			(start -0.7874 0.4064)
			(end -0.7874 -0.4064)
			(stroke
				(width 0.1524)
				(type default)
			)
			(layer "F.SilkS")
		)
		(fp_line
			(start -0.12065 -0.305054)
			(end -0.12065 -0.2794)
			(stroke
				(width 0.1)
				(type default)
			)
			(layer "F.Fab")
		)
		(fp_line
			(start -0.67945 -0.305054)
			(end -0.12065 -0.305054)
			(stroke
				(width 0.1)
				(type default)
			)
			(layer "F.Fab")
		)
		(fp_line
			(start 0.67945 -0.3048)
			(end 0.67945 0.3048)
			(stroke
				(width 0.1)
				(type default)
			)
			(layer "F.Fab")
		)
		(fp_line
			(start 0.12065 -0.3048)
			(end 0.67945 -0.3048)
			(stroke
				(width 0.1)
				(type default)
			)
			(layer "F.Fab")
		)
		(fp_line
			(start 0.12065 -0.2794)
			(end 0.12065 -0.3048)
			(stroke
				(width 0.1)
				(type default)
			)
			(layer "F.Fab")
		)
		(fp_line
			(start -0.12065 -0.2794)
			(end 0.12065 -0.2794)
			(stroke
				(width 0.1)
				(type default)
			)
			(layer "F.Fab")
		)
		(fp_line
			(start 0.120396 0.2794)
			(end -0.12065 0.2794)
			(stroke
				(width 0.1)
				(type default)
			)
			(layer "F.Fab")
		)
		(fp_line
			(start -0.12065 0.2794)
			(end -0.12065 0.3048)
			(stroke
				(width 0.1)
				(type default)
			)
			(layer "F.Fab")
		)
		(fp_line
			(start 0.67945 0.3048)
			(end 0.120396 0.3048)
			(stroke
				(width 0.1)
				(type default)
			)
			(layer "F.Fab")
		)
		(fp_line
			(start 0.120396 0.3048)
			(end 0.120396 0.2794)
			(stroke
				(width 0.1)
				(type default)
			)
			(layer "F.Fab")
		)
		(fp_line
			(start -0.12065 0.3048)
			(end -0.67945 0.3048)
			(stroke
				(width 0.1)
				(type default)
			)
			(layer "F.Fab")
		)
		(fp_line
			(start -0.67945 0.3048)
			(end -0.67945 -0.305054)
			(stroke
				(width 0.1)
				(type default)
			)
			(layer "F.Fab")
		)
		(pad "1" smd circle
			(at -0.40005 0 90)
			(size 0 0)
			(layers "F.Cu" "F.Mask" "F.Paste")
			(net "MB0_P12V_STBY_PWRGD")
		)
		(pad "2" smd circle
			(at 0.40005 0 90)
			(size 0 0)
			(layers "F.Cu" "F.Mask" "F.Paste")
			(net "FM_P12V_HSC_EN_R")
		)
	)
	(footprint ""
		(layer "F.Cu")
		(at 432.50104 -122.988578 90)
		(property "Reference" "PU35"
			(at -1.01219 -8.547354 0)
			(unlocked yes)
			(layer "F.SilkS")
			(effects
				(font
					(size 0.7874 0.5842)
					(thickness 0.1524)
				)
				(justify left)
			)
		)
		(property "Value" ""
			(at 0 0 90)
			(layer "F.Fab")
			(effects
				(font
					(size 1.27 1.27)
				)
			)
		)
		(duplicate_pad_numbers_are_jumpers no)
		(fp_line
			(start 0.1778 -3.2385)
			(end 0.1778 -2.8575)
			(stroke
				(width 0.1524)
				(type default)
			)
			(layer "F.SilkS")
		)
		(fp_line
			(start -1.8034 -2.8702)
			(end -1.8034 -3.6322)
			(stroke
				(width 0.1524)
				(type default)
			)
			(layer "F.SilkS")
		)
		(fp_line
			(start 2.500122 -2.500122)
			(end 2.500122 -2.015998)
			(stroke
				(width 0.1524)
				(type default)
			)
			(layer "F.SilkS")
		)
		(fp_line
			(start 2.015998 -2.500122)
			(end 2.500122 -2.500122)
			(stroke
				(width 0.1524)
				(type default)
			)
			(layer "F.SilkS")
		)
		(fp_line
			(start -2.500122 -2.500122)
			(end -2.015998 -2.500122)
			(stroke
				(width 0.1524)
				(type default)
			)
			(layer "F.SilkS")
		)
		(fp_line
			(start -2.500122 -2.015998)
			(end -2.500122 -2.500122)
			(stroke
				(width 0.1524)
				(type default)
			)
			(layer "F.SilkS")
		)
		(fp_line
			(start 2.8702 -1.778)
			(end 3.6322 -1.778)
			(stroke
				(width 0.1524)
				(type default)
			)
			(layer "F.SilkS")
		)
		(fp_line
			(start -3.2639 -0.1778)
			(end -2.8829 -0.1778)
			(stroke
				(width 0.1524)
				(type default)
			)
			(layer "F.SilkS")
		)
		(fp_line
			(start 2.8829 0.2032)
			(end 3.2639 0.2032)
			(stroke
				(width 0.1524)
				(type default)
			)
			(layer "F.SilkS")
		)
		(fp_line
			(start -3.6576 1.8034)
			(end -2.8956 1.8034)
			(stroke
				(width 0.1524)
				(type default)
			)
			(layer "F.SilkS")
		)
		(fp_line
			(start 2.500122 2.015998)
			(end 2.500122 2.500122)
			(stroke
				(width 0.1524)
				(type default)
			)
			(layer "F.SilkS")
		)
		(fp_line
			(start 2.500122 2.500122)
			(end 2.015998 2.500122)
			(stroke
				(width 0.1524)
				(type default)
			)
			(layer "F.SilkS")
		)
		(fp_line
			(start -2.015998 2.500122)
			(end -2.500122 2.500122)
			(stroke
				(width 0.1524)
				(type default)
			)
			(layer "F.SilkS")
		)
		(fp_line
			(start -2.500122 2.500122)
			(end -2.500122 2.018538)
			(stroke
				(width 0.1524)
				(type default)
			)
			(layer "F.SilkS")
		)
		(fp_line
			(start -0.2032 2.8829)
			(end -0.2032 3.2639)
			(stroke
				(width 0.1524)
				(type default)
			)
			(layer "F.SilkS")
		)
		(fp_line
			(start 1.778 3.6322)
			(end 1.778 2.8702)
			(stroke
				(width 0.1524)
				(type default)
			)
			(layer "F.SilkS")
		)
		(fp_poly
			(pts
				(xy -2.855468 -2.635504) (xy -2.64922 -2.017014) (xy -3.26771 -2.223008)
			)
			(stroke
				(width 0)
				(type default)
			)
			(fill yes)
			(layer "F.SilkS")
		)
		(fp_line
			(start 0.1778 -3.2385)
			(end 0.1778 -2.8575)
			(stroke
				(width 0.1)
				(type default)
			)
			(layer "F.Fab")
		)
		(fp_line
			(start -1.8034 -2.8702)
			(end -1.8034 -3.6322)
			(stroke
				(width 0.1)
				(type default)
			)
			(layer "F.Fab")
		)
		(fp_line
			(start 2.500122 -2.500122)
			(end 2.500122 2.500122)
			(stroke
				(width 0.1)
				(type default)
			)
			(layer "F.Fab")
		)
		(fp_line
			(start -2.500122 -2.500122)
			(end 2.500122 -2.500122)
			(stroke
				(width 0.1)
				(type default)
			)
			(layer "F.Fab")
		)
		(fp_line
			(start 2.8702 -1.778)
			(end 3.6322 -1.778)
			(stroke
				(width 0.1)
				(type default)
			)
			(layer "F.Fab")
		)
		(fp_line
			(start -3.2639 -0.1778)
			(end -2.8829 -0.1778)
			(stroke
				(width 0.1)
				(type default)
			)
			(layer "F.Fab")
		)
		(fp_line
			(start 2.8829 0.2032)
			(end 3.2639 0.2032)
			(stroke
				(width 0.1)
				(type default)
			)
			(layer "F.Fab")
		)
		(fp_line
			(start -3.6576 1.8034)
			(end -2.8956 1.8034)
			(stroke
				(width 0.1)
				(type default)
			)
			(layer "F.Fab")
		)
		(fp_line
			(start 2.500122 2.500122)
			(end -2.500122 2.500122)
			(stroke
				(width 0.1)
				(type default)
			)
			(layer "F.Fab")
		)
		(fp_line
			(start -2.500122 2.500122)
			(end -2.500122 -2.500122)
			(stroke
				(width 0.1)
				(type default)
			)
			(layer "F.Fab")
		)
		(fp_line
			(start -0.2032 2.8829)
			(end -0.2032 3.2639)
			(stroke
				(width 0.1)
				(type default)
			)
			(layer "F.Fab")
		)
		(fp_line
			(start 1.778 3.6322)
			(end 1.778 2.8702)
			(stroke
				(width 0.1)
				(type default)
			)
			(layer "F.Fab")
		)
		(fp_poly
			(pts
				(xy -2.921 -1.800098) (xy -3.504184 -1.508506) (xy -3.504184 -2.09169)
			)
			(stroke
				(width 0)
				(type default)
			)
			(fill yes)
			(layer "F.Fab")
		)
		(fp_text user "31"
			(at 3.1877 -3.0988 0)
			(unlocked yes)
			(layer "F.SilkS")
			(effects
				(font
					(size 0.635 0.4064)
					(thickness 0.1524)
				)
				(justify left)
			)
		)
		(fp_text user "40"
			(at -5.81152 -1.8161 0)
			(unlocked yes)
			(layer "F.SilkS")
			(effects
				(font
					(size 0.635 0.4064)
					(thickness 0.1524)
				)
				(justify left)
			)
		)
		(fp_text user "30"
			(at 3.535172 -1.33604 0)
			(unlocked yes)
			(layer "F.SilkS")
			(effects
				(font
					(size 0.635 0.4064)
					(thickness 0.1524)
				)
				(justify left)
			)
		)
		(fp_text user "21"
			(at 3.627628 0.47498 0)
			(unlocked yes)
			(layer "F.SilkS")
			(effects
				(font
					(size 0.635 0.4064)
					(thickness 0.1524)
				)
				(justify left)
			)
		)
		(fp_text user "10"
			(at -3.100832 2.05232 0)
			(unlocked yes)
			(layer "F.SilkS")
			(effects
				(font
					(size 0.635 0.4064)
					(thickness 0.1524)
				)
				(justify left)
			)
		)
		(fp_text user "20"
			(at 2.77622 2.74828 0)
			(unlocked yes)
			(layer "F.SilkS")
			(effects
				(font
					(size 0.635 0.4064)
					(thickness 0.1524)
				)
				(justify left)
			)
		)
		(fp_text user "11"
			(at -2.18948 2.90068 0)
			(unlocked yes)
			(layer "F.SilkS")
			(effects
				(font
					(size 0.635 0.4064)
					(thickness 0.1524)
				)
				(justify left)
			)
		)
		(fp_text user "31"
			(at 1.8542 -3.172968 90)
			(unlocked yes)
			(layer "F.Fab")
			(effects
				(font
					(size 0.635 0.4064)
					(thickness 0.1524)
				)
				(justify left)
			)
		)
		(fp_text user "30"
			(at 3.223768 -3.0988 0)
			(unlocked yes)
			(layer "F.Fab")
			(effects
				(font
					(size 0.635 0.4064)
					(thickness 0.1524)
				)
				(justify left)
			)
		)
		(fp_text user "40"
			(at -3.2004 -3.096768 90)
			(unlocked yes)
			(layer "F.Fab")
			(effects
				(font
					(size 0.635 0.4064)
					(thickness 0.1524)
				)
				(justify left)
			)
		)
		(fp_text user "21"
			(at 3.274568 1.8796 0)
			(unlocked yes)
			(layer "F.Fab")
			(effects
				(font
					(size 0.635 0.4064)
					(thickness 0.1524)
				)
				(justify left)
			)
		)
		(fp_text user "10"
			(at -3.253232 2.1336 0)
			(unlocked yes)
			(layer "F.Fab")
			(effects
				(font
					(size 0.635 0.4064)
					(thickness 0.1524)
				)
				(justify left)
			)
		)
		(fp_text user "20"
			(at 2.0828 3.253232 90)
			(unlocked yes)
			(layer "F.Fab")
			(effects
				(font
					(size 0.635 0.4064)
					(thickness 0.1524)
				)
				(justify left)
			)
		)
		(fp_text user "11"
			(at -2.8702 3.278632 90)
			(unlocked yes)
			(layer "F.Fab")
			(effects
				(font
					(size 0.635 0.4064)
					(thickness 0.1524)
				)
				(justify left)
			)
		)
		(pad "1" smd rect
			(at -2.400046 -1.800098)
			(size 0.1778 0.6096)
			(layers "F.Cu" "F.Mask" "F.Paste")
			(net "NC_PVCCD_HV_CPU0_APWM8")
		)
		(pad "2" smd rect
			(at -2.400046 -1.400048)
			(size 0.1778 0.6096)
			(layers "F.Cu" "F.Mask" "F.Paste")
			(net "NC_PVCCD_HV_CPU0_APWM7")
		)
		(pad "3" smd rect
			(at -2.400046 -0.999998)
			(size 0.1778 0.6096)
			(layers "F.Cu" "F.Mask" "F.Paste")
			(net "NC_PVCCD_HV_CPU0_APWM6")
		)
		(pad "4" smd rect
			(at -2.400046 -0.599948)
			(size 0.1778 0.6096)
			(layers "F.Cu" "F.Mask" "F.Paste")
			(net "NC_PVCCD_HV_CPU0_APWM5")
		)
		(pad "5" smd rect
			(at -2.400046 -0.199898)
			(size 0.1778 0.6096)
			(layers "F.Cu" "F.Mask" "F.Paste")
			(net "NC_PVCCD_HV_CPU0_APWM4")
		)
		(pad "6" smd rect
			(at -2.400046 0.199898)
			(size 0.1778 0.6096)
			(layers "F.Cu" "F.Mask" "F.Paste")
			(net "NC_PVCCD_HV_CPU0_APWM3")
		)
		(pad "7" smd rect
			(at -2.400046 0.599948)
			(size 0.1778 0.6096)
			(layers "F.Cu" "F.Mask" "F.Paste")
			(net "NC_PVCCD_HV_CPU0_APWM2")
		)
		(pad "8" smd rect
			(at -2.400046 0.999998)
			(size 0.1778 0.6096)
			(layers "F.Cu" "F.Mask" "F.Paste")
			(net "PVCCD_HV_CPU0_APWM1")
		)
		(pad "9" smd rect
			(at -2.400046 1.400048)
			(size 0.1778 0.6096)
			(layers "F.Cu" "F.Mask" "F.Paste")
			(net "SMB_DIO_PVCCD_HV_CPU0")
		)
		(pad "10" smd rect
			(at -2.400046 1.800098)
			(size 0.1778 0.6096)
			(layers "F.Cu" "F.Mask" "F.Paste")
			(net "SMB_CLK_PVCCD_HV_CPU0")
		)
		(pad "11" smd rect
			(at -1.800098 2.400046 90)
			(size 0.1778 0.6096)
			(layers "F.Cu" "F.Mask" "F.Paste")
			(net "NC_PVCCD_HV_CPU0_SMB_ALERT")
		)
		(pad "12" smd rect
			(at -1.400048 2.400046 90)
			(size 0.1778 0.6096)
			(layers "F.Cu" "F.Mask" "F.Paste")
			(net "PWRGD_PVCCD_HV_CPU0_R")
		)
		(pad "13" smd rect
			(at -0.999998 2.400046 90)
			(size 0.1778 0.6096)
			(layers "F.Cu" "F.Mask" "F.Paste")
			(net "PVCCD_HV_CPU0_EN_R")
		)
		(pad "14" smd rect
			(at -0.599948 2.400046 90)
			(size 0.1778 0.6096)
			(layers "F.Cu" "F.Mask" "F.Paste")
			(net "IRQ_PVCCD_CPU0_VRHOT_LVC3_R_N")
		)
		(pad "15" smd rect
			(at -0.199898 2.400046 90)
			(size 0.1778 0.6096)
			(layers "F.Cu" "F.Mask" "F.Paste")
			(net "PVCCD_HV_CPU0_PIN_ALT")
		)
		(pad "16" smd rect
			(at 0.199898 2.400046 90)
			(size 0.1778 0.6096)
			(layers "F.Cu" "F.Mask" "F.Paste")
			(net "NC_PVCCD_HV_CPU0_BVR_RDY")
		)
		(pad "17" smd rect
			(at 0.599948 2.400046 90)
			(size 0.1778 0.6096)
			(layers "F.Cu" "F.Mask" "F.Paste")
			(net "SVID_CLK_PVCCD_HV_CPU0_R")
		)
		(pad "18" smd rect
			(at 0.999998 2.400046 90)
			(size 0.1778 0.6096)
			(layers "F.Cu" "F.Mask" "F.Paste")
			(net "SVID_DIO_PVCCD_HV_CPU0_R")
		)
		(pad "19" smd rect
			(at 1.400048 2.400046 90)
			(size 0.1778 0.6096)
			(layers "F.Cu" "F.Mask" "F.Paste")
			(net "SVID_ALERT_PVCCD_HV_CPU0_R")
		)
		(pad "20" smd rect
			(at 1.800098 2.400046 90)
			(size 0.1778 0.6096)
			(layers "F.Cu" "F.Mask" "F.Paste")
			(net "GND")
		)
		(pad "21" smd rect
			(at 2.400046 1.800098)
			(size 0.1778 0.6096)
			(layers "F.Cu" "F.Mask" "F.Paste")
			(net "SH_PVCCD_HV_CPU0_R")
		)
		(pad "22" smd rect
			(at 2.400046 1.400048)
			(size 0.1778 0.6096)
			(layers "F.Cu" "F.Mask" "F.Paste")
			(net "VSENSE_PVCCD_HV_CPU0_DN")
		)
		(pad "23" smd rect
			(at 2.400046 0.999998)
			(size 0.1778 0.6096)
			(layers "F.Cu" "F.Mask" "F.Paste")
			(net "PVCCD_HV_CPU0_ACSP1")
		)
		(pad "24" smd rect
			(at 2.400046 0.599948)
			(size 0.1778 0.6096)
			(layers "F.Cu" "F.Mask" "F.Paste")
			(net "NC_PVCCD_HV_CPU0_ACSP2")
		)
		(pad "25" smd rect
			(at 2.400046 0.199898)
			(size 0.1778 0.6096)
			(layers "F.Cu" "F.Mask" "F.Paste")
			(net "NC_PVCCD_HV_CPU0_ACSP3")
		)
		(pad "26" smd rect
			(at 2.400046 -0.199898)
			(size 0.1778 0.6096)
			(layers "F.Cu" "F.Mask" "F.Paste")
			(net "NC_PVCCD_HV_CPU0_ACSP4")
		)
		(pad "27" smd rect
			(at 2.400046 -0.599948)
			(size 0.1778 0.6096)
			(layers "F.Cu" "F.Mask" "F.Paste")
			(net "NC_PVCCD_HV_CPU0_ACSP5")
		)
		(pad "28" smd rect
			(at 2.400046 -0.999998)
			(size 0.1778 0.6096)
			(layers "F.Cu" "F.Mask" "F.Paste")
			(net "NC_PVCCD_HV_CPU0_ACSP6")
		)
		(pad "29" smd rect
			(at 2.400046 -1.400048)
			(size 0.1778 0.6096)
			(layers "F.Cu" "F.Mask" "F.Paste")
			(net "NC_PVCCD_HV_CPU0_ACSP7")
		)
		(pad "30" smd rect
			(at 2.400046 -1.800098)
			(size 0.1778 0.6096)
			(layers "F.Cu" "F.Mask" "F.Paste")
			(net "NC_PVCCD_HV_CPU0_ACSP8")
		)
		(pad "31" smd rect
			(at 1.800098 -2.400046 90)
			(size 0.1778 0.6096)
			(layers "F.Cu" "F.Mask" "F.Paste")
			(net "GND")
		)
		(pad "32" smd rect
			(at 1.400048 -2.400046 90)
			(size 0.1778 0.6096)
			(layers "F.Cu" "F.Mask" "F.Paste")
			(net "GND")
		)
		(pad "33" smd rect
			(at 0.999998 -2.400046 90)
			(size 0.1778 0.6096)
			(layers "F.Cu" "F.Mask" "F.Paste")
			(net "PVCCD_HV_CPU0_FAULT")
		)
		(pad "34" smd rect
			(at 0.599948 -2.400046 90)
			(size 0.1778 0.6096)
			(layers "F.Cu" "F.Mask" "F.Paste")
			(net "PVCCD_HV_CPU0_ADDR")
		)
		(pad "35" smd rect
			(at 0.199898 -2.400046 90)
			(size 0.1778 0.6096)
			(layers "F.Cu" "F.Mask" "F.Paste")
			(net "PVCCD_HV_CPU0_ATSEN")
		)
		(pad "36" smd rect
			(at -0.199898 -2.400046 90)
			(size 0.1778 0.6096)
			(layers "F.Cu" "F.Mask" "F.Paste")
			(net "PVCCD_HV_CPU0_ISYS_R")
		)
		(pad "37" smd rect
			(at -0.599948 -2.400046 90)
			(size 0.1778 0.6096)
			(layers "F.Cu" "F.Mask" "F.Paste")
			(net "PVCCD_HV_CPU0_ISENSE_P")
		)
		(pad "38" smd rect
			(at -0.999998 -2.400046 90)
			(size 0.1778 0.6096)
			(layers "F.Cu" "F.Mask" "F.Paste")
			(net "PVCCD_HV_CPU0_ISENSE_N")
		)
		(pad "39" smd rect
			(at -1.400048 -2.400046 90)
			(size 0.1778 0.6096)
			(layers "F.Cu" "F.Mask" "F.Paste")
			(net "PVCCD_HV_CPU0_VCC")
		)
		(pad "40" smd rect
			(at -1.800098 -2.400046 90)
			(size 0.1778 0.6096)
			(layers "F.Cu" "F.Mask" "F.Paste")
			(net "PVCCD_HV_CPU0_VREF")
		)
		(pad "TH" smd rect
			(at 0 0 90)
			(size 3.6576 3.6576)
			(layers "F.Cu" "F.Mask" "F.Paste")
			(net "GND")
		)
		(zone
			(layer "F.Cu")
			(hatch none 0.5)
			(connect_pads
				(clearance 0)
			)
			(min_thickness 0.25)
			(keepout
				(tracks not_allowed)
				(vias allowed)
				(pads allowed)
				(copperpour not_allowed)
				(footprints allowed)
			)
			(placement
				(enabled no)
				(sheetname "")
			)
			(fill
				(thermal_gap 0.5)
				(thermal_bridge_width 0.5)
				(island_removal_mode 0)
			)
			(polygon
				(pts
					(xy 434.38064 -124.678948) (xy 434.53304 -124.678948) (xy 434.53304 -120.956578) (xy 430.64684 -120.956578)
					(xy 430.64684 -121.108978) (xy 434.38064 -121.108978)
				)
			)
		)
	)
)
